# T6G (Grand Teton) — schematic netlist excerpt (pin names and nets, part order shuffled) for the footprints in the layout excerpt that follows; sources: Cadence DE-HDL packaged netlist, KiCad conversion of 04192023_DAF0TMB3IC0_F0TG_MB_C_brd_V02_OCP.brd

C2056  Q_CAP  0.1UF 25V 10% X7R  pkg 0402  page 252 : A = P3V3_AUX ; B = GND
R53  Q_RES  4.7K 1% CHIP  pkg 0402LF  page 133 : A = P3V3_AUX ; B = OCP_SFF_PWRBRK_BUFF_N

(kicad_pcb
	(version 20260206)
	(generator "pcbnew")
	(generator_version "10.0")
	(general
		(thickness 1.6)
		(legacy_teardrops no)
	)
	(paper "A4")
	(title_block
		(title "04192023_DAF0TMB3IC0_F0TG_MB_C_brd_V02_OCP.brd")
		(comment 1 "Grand Teton / footprints 2844-2845 of 8354")
	)
	(layers
		(0 "F.Cu" signal "TOP")
		(4 "In1.Cu" signal "GND")
		(6 "In2.Cu" signal "IN1")
		(8 "In3.Cu" signal "GND1")
		(10 "In4.Cu" signal "IN2")
		(12 "In5.Cu" signal "GND2")
		(14 "In6.Cu" signal "IN3")
		(16 "In7.Cu" signal "GND3")
		(18 "In8.Cu" signal "VCC")
		(20 "In9.Cu" signal "VCC1")
		(22 "In10.Cu" signal "GND4")
		(24 "In11.Cu" signal "IN4")
		(26 "In12.Cu" signal "GND5")
		(28 "In13.Cu" signal "IN5")
		(30 "In14.Cu" signal "GND6")
		(32 "In15.Cu" signal "IN6")
		(34 "In16.Cu" signal "GND7")
		(2 "B.Cu" signal "BOTTOM")
		(9 "F.Adhes" user "F.Adhesive")
		(11 "B.Adhes" user "B.Adhesive")
		(13 "F.Paste" user "Package Geometry/Pastemask Top")
		(15 "B.Paste" user "Package Geometry/Pastemask Bottom")
		(5 "F.SilkS" user "Ref Des/Silkscreen Top")
		(7 "B.SilkS" user "Ref Des/Silkscreen Bottom")
		(1 "F.Mask" user "Board Geometry/Soldermask Top")
		(3 "B.Mask" user "Board Geometry/Soldermask Bottom")
		(17 "Dwgs.User" user "User.Drawings")
		(19 "Cmts.User" user "User.Comments")
		(21 "Eco1.User" user "User.Eco1")
		(23 "Eco2.User" user "User.Eco2")
		(25 "Edge.Cuts" user "Board Geometry/Outline")
		(27 "Margin" user)
		(31 "F.CrtYd" user "Package Geometry/Place Bound Top")
		(29 "B.CrtYd" user "Package Geometry/Place Bound Bottom")
		(35 "F.Fab" user "Ref Des/Assembly Top")
		(33 "B.Fab" user "Ref Des/Assembly Bottom")
	)
	(footprint ""
		(layer "F.Cu")
		(at 268.59992 -124.469398)
		(property "Reference" "C2056"
			(at 0 0 0)
			(layer "F.SilkS")
			(hide yes)
			(effects
				(font
					(size 1.27 1.27)
				)
			)
		)
		(property "Value" ""
			(at 0 0 0)
			(layer "F.Fab")
			(effects
				(font
					(size 1.27 1.27)
				)
			)
		)
		(duplicate_pad_numbers_are_jumpers no)
		(fp_line
			(start -0.7874 -0.4064)
			(end 0.7874 -0.4064)
			(stroke
				(width 0.1524)
				(type default)
			)
			(layer "F.SilkS")
		)
		(fp_line
			(start -0.7874 0.4064)
			(end -0.7874 -0.4064)
			(stroke
				(width 0.1524)
				(type default)
			)
			(layer "F.SilkS")
		)
		(fp_line
			(start 0.7874 -0.4064)
			(end 0.7874 0.4064)
			(stroke
				(width 0.1524)
				(type default)
			)
			(layer "F.SilkS")
		)
		(fp_line
			(start 0.7874 0.4064)
			(end -0.7874 0.4064)
			(stroke
				(width 0.1524)
				(type default)
			)
			(layer "F.SilkS")
		)
		(fp_line
			(start -0.67945 -0.305054)
			(end -0.12065 -0.305054)
			(stroke
				(width 0.1)
				(type default)
			)
			(layer "F.Fab")
		)
		(fp_line
			(start -0.67945 0.3048)
			(end -0.67945 -0.305054)
			(stroke
				(width 0.1)
				(type default)
			)
			(layer "F.Fab")
		)
		(fp_line
			(start -0.12065 -0.305054)
			(end -0.12065 -0.2794)
			(stroke
				(width 0.1)
				(type default)
			)
			(layer "F.Fab")
		)
		(fp_line
			(start -0.12065 -0.2794)
			(end 0.12065 -0.2794)
			(stroke
				(width 0.1)
				(type default)
			)
			(layer "F.Fab")
		)
		(fp_line
			(start -0.12065 0.2794)
			(end -0.12065 0.3048)
			(stroke
				(width 0.1)
				(type default)
			)
			(layer "F.Fab")
		)
		(fp_line
			(start -0.12065 0.3048)
			(end -0.67945 0.3048)
			(stroke
				(width 0.1)
				(type default)
			)
			(layer "F.Fab")
		)
		(fp_line
			(start 0.120396 0.2794)
			(end -0.12065 0.2794)
			(stroke
				(width 0.1)
				(type default)
			)
			(layer "F.Fab")
		)
		(fp_line
			(start 0.120396 0.3048)
			(end 0.120396 0.2794)
			(stroke
				(width 0.1)
				(type default)
			)
			(layer "F.Fab")
		)
		(fp_line
			(start 0.12065 -0.3048)
			(end 0.67945 -0.3048)
			(stroke
				(width 0.1)
				(type default)
			)
			(layer "F.Fab")
		)
		(fp_line
			(start 0.12065 -0.2794)
			(end 0.12065 -0.3048)
			(stroke
				(width 0.1)
				(type default)
			)
			(layer "F.Fab")
		)
		(fp_line
			(start 0.67945 -0.3048)
			(end 0.67945 0.3048)
			(stroke
				(width 0.1)
				(type default)
			)
			(layer "F.Fab")
		)
		(fp_line
			(start 0.67945 0.3048)
			(end 0.120396 0.3048)
			(stroke
				(width 0.1)
				(type default)
			)
			(layer "F.Fab")
		)
		(pad "1" smd circle
			(at -0.40005 0)
			(size 0 0)
			(layers "F.Cu" "F.Mask" "F.Paste")
			(net "P3V3_AUX")
		)
		(pad "2" smd circle
			(at 0.40005 0)
			(size 0 0)
			(layers "F.Cu" "F.Mask" "F.Paste")
			(net "GND")
		)
	)
	(footprint ""
		(layer "F.Cu")
		(at 372.46687 -15.637002)
		(property "Reference" "R53"
			(at 0 0 0)
			(layer "F.SilkS")
			(hide yes)
			(effects
				(font
					(size 1.27 1.27)
				)
			)
		)
		(property "Value" ""
			(at 0 0 0)
			(layer "F.Fab")
			(effects
				(font
					(size 1.27 1.27)
				)
			)
		)
		(duplicate_pad_numbers_are_jumpers no)
		(fp_line
			(start -0.7874 -0.4064)
			(end 0.7874 -0.4064)
			(stroke
				(width 0.1524)
				(type default)
			)
			(layer "F.SilkS")
		)
		(fp_line
			(start -0.7874 0.4064)
			(end -0.7874 -0.4064)
			(stroke
				(width 0.1524)
				(type default)
			)
			(layer "F.SilkS")
		)
		(fp_line
			(start 0.7874 -0.4064)
			(end 0.7874 0.4064)
			(stroke
				(width 0.1524)
				(type default)
			)
			(layer "F.SilkS")
		)
		(fp_line
			(start 0.7874 0.4064)
			(end -0.7874 0.4064)
			(stroke
				(width 0.1524)
				(type default)
			)
			(layer "F.SilkS")
		)
		(fp_line
			(start -0.67945 -0.305054)
			(end -0.12065 -0.305054)
			(stroke
				(width 0.1)
				(type default)
			)
			(layer "F.Fab")
		)
		(fp_line
			(start -0.67945 0.3048)
			(end -0.67945 -0.305054)
			(stroke
				(width 0.1)
				(type default)
			)
			(layer "F.Fab")
		)
		(fp_line
			(start -0.12065 -0.305054)
			(end -0.12065 -0.2794)
			(stroke
				(width 0.1)
				(type default)
			)
			(layer "F.Fab")
		)
		(fp_line
			(start -0.12065 -0.2794)
			(end 0.12065 -0.2794)
			(stroke
				(width 0.1)
				(type default)
			)
			(layer "F.Fab")
		)
		(fp_line
			(start -0.12065 0.2794)
			(end -0.12065 0.3048)
			(stroke
				(width 0.1)
				(type default)
			)
			(layer "F.Fab")
		)
		(fp_line
			(start -0.12065 0.3048)
			(end -0.67945 0.3048)
			(stroke
				(width 0.1)
				(type default)
			)
			(layer "F.Fab")
		)
		(fp_line
			(start 0.120396 0.2794)
			(end -0.12065 0.2794)
			(stroke
				(width 0.1)
				(type default)
			)
			(layer "F.Fab")
		)
		(fp_line
			(start 0.120396 0.3048)
			(end 0.120396 0.2794)
			(stroke
				(width 0.1)
				(type default)
			)
			(layer "F.Fab")
		)
		(fp_line
			(start 0.12065 -0.3048)
			(end 0.67945 -0.3048)
			(stroke
				(width 0.1)
				(type default)
			)
			(layer "F.Fab")
		)
		(fp_line
			(start 0.12065 -0.2794)
			(end 0.12065 -0.3048)
			(stroke
				(width 0.1)
				(type default)
			)
			(layer "F.Fab")
		)
		(fp_line
			(start 0.67945 -0.3048)
			(end 0.67945 0.3048)
			(stroke
				(width 0.1)
				(type default)
			)
			(layer "F.Fab")
		)
		(fp_line
			(start 0.67945 0.3048)
			(end 0.120396 0.3048)
			(stroke
				(width 0.1)
				(type default)
			)
			(layer "F.Fab")
		)
		(pad "1" smd circle
			(at -0.40005 0)
			(size 0 0)
			(layers "F.Cu" "F.Mask" "F.Paste")
			(net "P3V3_AUX")
		)
		(pad "2" smd circle
			(at 0.40005 0)
			(size 0 0)
			(layers "F.Cu" "F.Mask" "F.Paste")
			(net "OCP_SFF_PWRBRK_BUFF_N")
		)
	)
)
